(kicad_pcb
	(version 20241229)
	(generator "pcbnew")
	(generator_version "9.0")
	(general
		(thickness 1.62)
		(legacy_teardrops no)
	)
	(paper "A3")
	(title_block
		(title "COM Express 7 Baseboard")
		(date "2025-02-04")
		(rev "1.1.2")
		(company "Antmicro Ltd")
		(comment 1 "www.antmicro.com")
		(comment 9 "footprints 159-164 of 802")
	)
	(layers
		(0 "F.Cu" signal)
		(4 "In1.Cu" signal)
		(6 "In2.Cu" signal)
		(8 "In3.Cu" signal)
		(10 "In4.Cu" signal)
		(12 "In5.Cu" signal)
		(14 "In6.Cu" signal)
		(2 "B.Cu" signal)
		(9 "F.Adhes" user "F.Adhesive")
		(11 "B.Adhes" user "B.Adhesive")
		(13 "F.Paste" user)
		(15 "B.Paste" user)
		(5 "F.SilkS" user "F.Silkscreen")
		(7 "B.SilkS" user "B.Silkscreen")
		(1 "F.Mask" user)
		(3 "B.Mask" user)
		(17 "Dwgs.User" user "User.Drawings")
		(19 "Cmts.User" user "User.Comments")
		(21 "Eco1.User" user "User.Eco1")
		(23 "Eco2.User" user "User.Eco2")
		(25 "Edge.Cuts" user)
		(27 "Margin" user)
		(31 "F.CrtYd" user "F.Courtyard")
		(29 "B.CrtYd" user "B.Courtyard")
		(35 "F.Fab" user)
		(33 "B.Fab" user)
	)
	(footprint "antmicro-footprints:LED_0603_1608Metric_G"
		(layer "F.Cu")
		(at 193.70861 74.802163 90)
		(descr "LED SMD 0603 Green")
		(tags "LED SMD 0603 Green")
		(property "Reference" "D32"
			(at -1.1 -0.55 90)
			(layer "F.SilkS")
			(effects
				(font
					(size 0.7 0.7)
					(thickness 0.15)
				)
				(justify left bottom)
			)
		)
		(property "Value" "LED_G_0603_LTST-C190GKT"
			(at -0.001 1.599 90)
			(layer "F.Fab")
			(effects
				(font
					(size 0.7 0.7)
					(thickness 0.15)
				)
				(justify left bottom)
			)
		)
		(property "Datasheet" "https://media.digikey.com/pdf/Data%20Sheets/Lite-On%20PDFs/LTST-C190GKT.pdf"
			(at 0 0 90)
			(layer "F.Fab")
			(hide yes)
			(effects
				(font
					(size 1.27 1.27)
					(thickness 0.15)
				)
			)
		)
		(property "Author" "Antmicro"
			(at 268.510773 -118.906447 0)
			(layer "F.Fab")
			(hide yes)
			(effects
				(font
					(size 1 1)
					(thickness 0.15)
				)
			)
		)
		(property "Color" "Green"
			(at 268.510773 -118.906447 0)
			(layer "F.Fab")
			(hide yes)
			(effects
				(font
					(size 1 1)
					(thickness 0.15)
				)
			)
		)
		(property "License" "Apache-2.0"
			(at 268.510773 -118.906447 0)
			(layer "F.Fab")
			(hide yes)
			(effects
				(font
					(size 1 1)
					(thickness 0.15)
				)
			)
		)
		(property "MPN" "LTST-C190GKT"
			(at 268.510773 -118.906447 0)
			(layer "F.Fab")
			(hide yes)
			(effects
				(font
					(size 1 1)
					(thickness 0.15)
				)
			)
		)
		(property "Manufacturer" "Lite-On"
			(at 268.510773 -118.906447 0)
			(layer "F.Fab")
			(hide yes)
			(effects
				(font
					(size 1 1)
					(thickness 0.15)
				)
			)
		)
		(property "Public" "False"
			(at 268.510773 -118.906447 0)
			(layer "F.Fab")
			(hide yes)
			(effects
				(font
					(size 1 1)
					(thickness 0.15)
				)
			)
		)
		(sheetname "Power")
		(sheetfile "power.kicad_sch")
		(attr smd)
		(fp_line
			(start 0.22 -0.35)
			(end -0.22 -0.35)
			(stroke
				(width 0.15)
				(type solid)
			)
			(layer "F.SilkS")
		)
		(fp_line
			(start -1.18 -0.319)
			(end -1.18 0.321)
			(stroke
				(width 0.15)
				(type solid)
			)
			(layer "F.SilkS")
		)
		(fp_line
			(start 0.105328 0.001008)
			(end 0.24 0.001)
			(stroke
				(width 0.1)
				(type solid)
			)
			(layer "F.SilkS")
		)
		(fp_line
			(start -0.094672 0.001008)
			(end 0.105328 -0.198992)
			(stroke
				(width 0.1)
				(type solid)
			)
			(layer "F.SilkS")
		)
		(fp_line
			(start -0.094672 0.001008)
			(end -0.24 0.001008)
			(stroke
				(width 0.1)
				(type solid)
			)
			(layer "F.SilkS")
		)
		(fp_line
			(start 0.105328 0.201008)
			(end 0.105328 -0.198992)
			(stroke
				(width 0.1)
				(type solid)
			)
			(layer "F.SilkS")
		)
		(fp_line
			(start 0.105328 0.201008)
			(end -0.094672 0.001008)
			(stroke
				(width 0.1)
				(type solid)
			)
			(layer "F.SilkS")
		)
		(fp_line
			(start -0.094672 0.201008)
			(end -0.094672 -0.198992)
			(stroke
				(width 0.1)
				(type solid)
			)
			(layer "F.SilkS")
		)
		(fp_line
			(start 0.22 0.35)
			(end -0.22 0.35)
			(stroke
				(width 0.15)
				(type solid)
			)
			(layer "F.SilkS")
		)
		(fp_rect
			(start 1.25 0.65)
			(end -1.25 -0.65)
			(stroke
				(width 0.05)
				(type solid)
			)
			(fill no)
			(layer "F.CrtYd")
		)
		(fp_line
			(start 0.201 -0.202)
			(end -0.101 0)
			(stroke
				(width 0.15)
				(type solid)
			)
			(layer "F.Fab")
		)
		(fp_line
			(start -0.199 -0.202)
			(end -0.199 0.1)
			(stroke
				(width 0.15)
				(type solid)
			)
			(layer "F.Fab")
		)
		(fp_line
			(start 0.599 0)
			(end 0.201 0)
			(stroke
				(width 0.15)
				(type solid)
			)
			(layer "F.Fab")
		)
		(fp_line
			(start 0.201 0)
			(end 0.201 -0.202)
			(stroke
				(width 0.15)
				(type solid)
			)
			(layer "F.Fab")
		)
		(fp_line
			(start -0.101 0)
			(end 0.201 0.2)
			(stroke
				(width 0.15)
				(type solid)
			)
			(layer "F.Fab")
		)
		(fp_line
			(start -0.199 0)
			(end -0.597 0)
			(stroke
				(width 0.15)
				(type solid)
			)
			(layer "F.Fab")
		)
		(fp_line
			(start 0.201 0.2)
			(end 0.201 0)
			(stroke
				(width 0.15)
				(type solid)
			)
			(layer "F.Fab")
		)
		(fp_line
			(start -0.199 0.2)
			(end -0.199 0.1)
			(stroke
				(width 0.15)
				(type solid)
			)
			(layer "F.Fab")
		)
		(fp_rect
			(start 0.848 0.4)
			(end -0.85 -0.402)
			(stroke
				(width 0.15)
				(type solid)
			)
			(fill no)
			(layer "F.Fab")
		)
		(pad "1" smd roundrect
			(at -0.7 0 270)
			(size 0.8 1)
			(layers "F.Cu" "F.Mask" "F.Paste")
			(roundrect_rratio 0.2)
			(net 984 "Net-(D32-C)")
			(pinfunction "C")
			(pintype "passive")
			(teardrops
				(best_length_ratio 0.2)
				(max_length 1)
				(best_width_ratio 0.9)
				(max_width 2)
				(curved_edges yes)
				(filter_ratio 0.9)
				(enabled yes)
				(allow_two_segments yes)
				(prefer_zone_connections yes)
			)
		)
		(pad "2" smd roundrect
			(at 0.7 0 270)
			(size 0.8 1)
			(layers "F.Cu" "F.Mask" "F.Paste")
			(roundrect_rratio 0.2)
			(net 65 "+12V")
			(pinfunction "A")
			(pintype "passive")
			(teardrops
				(best_length_ratio 0.2)
				(max_length 1)
				(best_width_ratio 0.9)
				(max_width 2)
				(curved_edges yes)
				(filter_ratio 0.9)
				(enabled yes)
				(allow_two_segments yes)
				(prefer_zone_connections yes)
			)
		)
	)
	(footprint "antmicro-footprints:TP_SMD_0.75mm"
		(layer "F.Cu")
		(at 157 128.71)
		(property "Reference" "TP70"
			(at 0.4 -3.3 90)
			(layer "F.SilkS")
			(effects
				(font
					(size 0.7 0.7)
					(thickness 0.15)
				)
				(justify left bottom)
			)
		)
		(property "Value" "TP_0.75mm_SMD"
			(at 0 1.2 0)
			(layer "F.Fab")
			(effects
				(font
					(size 0.7 0.7)
					(thickness 0.15)
				)
				(justify left bottom)
			)
		)
		(property "Author" "Antmicro"
			(at 0 0 0)
			(layer "F.Fab")
			(hide yes)
			(effects
				(font
					(size 1 1)
					(thickness 0.15)
				)
			)
		)
		(property "License" "Apache-2.0"
			(at 0 0 0)
			(layer "F.Fab")
			(hide yes)
			(effects
				(font
					(size 1 1)
					(thickness 0.15)
				)
			)
		)
		(property "MPN" ""
			(at 0 0 0)
			(layer "F.Fab")
			(hide yes)
			(effects
				(font
					(size 1 1)
					(thickness 0.15)
				)
			)
		)
		(property "Manufacturer" ""
			(at 0 0 0)
			(layer "F.Fab")
			(hide yes)
			(effects
				(font
					(size 1 1)
					(thickness 0.15)
				)
			)
		)
		(property "Public" "False"
			(at 0 0 0)
			(layer "F.Fab")
			(hide yes)
			(effects
				(font
					(size 1 1)
					(thickness 0.15)
				)
			)
		)
		(sheetname "KR to SFI #1")
		(sheetfile "kr_sfi.kicad_sch")
		(attr exclude_from_pos_files exclude_from_bom)
		(fp_circle
			(center 0 0)
			(end 0.475 0)
			(stroke
				(width 0.05)
				(type default)
			)
			(fill no)
			(layer "F.CrtYd")
		)
		(pad "1" smd circle
			(at 0 0)
			(size 0.75 0.75)
			(layers "F.Cu" "F.Mask")
			(net 733 "Net-(U43C-CLKOUTB-)")
			(pinfunction "1")
			(pintype "passive")
			(teardrops
				(best_length_ratio 0.4)
				(max_length 1)
				(best_width_ratio 0.9)
				(max_width 2)
				(curved_edges yes)
				(filter_ratio 0.9)
				(enabled yes)
				(allow_two_segments yes)
				(prefer_zone_connections yes)
			)
		)
	)
	(footprint "antmicro-footprints:R_0402_1005Metric"
		(layer "F.Cu")
		(at 252.615 82.174999)
		(descr "Resistor SMD 0402")
		(tags "resistor SMD 0402")
		(property "Reference" "R146"
			(at -0.825 0.435001 0)
			(layer "F.SilkS")
			(effects
				(font
					(size 0.7 0.7)
					(thickness 0.15)
				)
				(justify right bottom)
			)
		)
		(property "Value" "R_10k_0402"
			(at -1.011843 1.772047 0)
			(layer "F.Fab")
			(effects
				(font
					(size 0.7 0.7)
					(thickness 0.15)
				)
				(justify left bottom)
			)
		)
		(property "Datasheet" "https://www.bourns.com/docs/product-datasheets/cr.pdf"
			(at 0 0 0)
			(layer "F.Fab")
			(hide yes)
			(effects
				(font
					(size 1.27 1.27)
					(thickness 0.15)
				)
			)
		)
		(property "Author" "Antmicro"
			(at 0 0 0)
			(layer "F.Fab")
			(hide yes)
			(effects
				(font
					(size 1 1)
					(thickness 0.15)
				)
			)
		)
		(property "License" "Apache-2.0"
			(at 0 0 0)
			(layer "F.Fab")
			(hide yes)
			(effects
				(font
					(size 1 1)
					(thickness 0.15)
				)
			)
		)
		(property "MPN" "CR0402-FX-1002GLF"
			(at 0 0 0)
			(layer "F.Fab")
			(hide yes)
			(effects
				(font
					(size 1 1)
					(thickness 0.15)
				)
			)
		)
		(property "Manufacturer" "Bourns"
			(at 0 0 0)
			(layer "F.Fab")
			(hide yes)
			(effects
				(font
					(size 1 1)
					(thickness 0.15)
				)
			)
		)
		(property "Public" "False"
			(at 0 0 0)
			(layer "F.Fab")
			(hide yes)
			(effects
				(font
					(size 1 1)
					(thickness 0.15)
				)
			)
		)
		(property "Tolerance" "1%"
			(at 0 0 0)
			(layer "F.Fab")
			(hide yes)
			(effects
				(font
					(size 1 1)
					(thickness 0.15)
				)
			)
		)
		(property "Val" "10k"
			(at 0 0 0)
			(layer "F.Fab")
			(hide yes)
			(effects
				(font
					(size 1 1)
					(thickness 0.15)
				)
			)
		)
		(sheetname "Misc")
		(sheetfile "misc.kicad_sch")
		(attr smd dnp)
		(fp_rect
			(start -0.925 -0.47)
			(end 0.925 0.47)
			(stroke
				(width 0.05)
				(type default)
			)
			(fill no)
			(layer "F.CrtYd")
		)
		(fp_rect
			(start -0.5 -0.25)
			(end 0.5 0.25)
			(stroke
				(width 0.15)
				(type solid)
			)
			(fill no)
			(layer "F.Fab")
		)
		(pad "1" smd roundrect
			(at -0.48 0)
			(size 0.59 0.64)
			(layers "F.Cu" "F.Mask" "F.Paste")
			(roundrect_rratio 0.25)
			(net 1 "GND")
			(pintype "passive")
			(teardrops
				(best_length_ratio 0.2)
				(max_length 1)
				(best_width_ratio 0.9)
				(max_width 2)
				(curved_edges yes)
				(filter_ratio 0.9)
				(enabled yes)
				(allow_two_segments yes)
				(prefer_zone_connections yes)
			)
		)
		(pad "2" smd roundrect
			(at 0.48 0)
			(size 0.59 0.64)
			(layers "F.Cu" "F.Mask" "F.Paste")
			(roundrect_rratio 0.25)
			(net 589 "/Misc/~{ADDRSEL}")
			(pintype "passive")
			(teardrops
				(best_length_ratio 0.2)
				(max_length 1)
				(best_width_ratio 0.9)
				(max_width 2)
				(curved_edges yes)
				(filter_ratio 0.9)
				(enabled yes)
				(allow_two_segments yes)
				(prefer_zone_connections yes)
			)
		)
	)
	(footprint "antmicro-footprints:TP_SMD_0.75mm"
		(layer "F.Cu")
		(at 132.34 128.71)
		(property "Reference" "TP93"
			(at 0.51 -3.3 90)
			(layer "F.SilkS")
			(effects
				(font
					(size 0.7 0.7)
					(thickness 0.15)
				)
				(justify left bottom)
			)
		)
		(property "Value" "TP_0.75mm_SMD"
			(at 0 1.2 0)
			(layer "F.Fab")
			(effects
				(font
					(size 0.7 0.7)
					(thickness 0.15)
				)
				(justify left bottom)
			)
		)
		(property "Author" "Antmicro"
			(at 0 0 0)
			(layer "F.Fab")
			(hide yes)
			(effects
				(font
					(size 1 1)
					(thickness 0.15)
				)
			)
		)
		(property "License" "Apache-2.0"
			(at 0 0 0)
			(layer "F.Fab")
			(hide yes)
			(effects
				(font
					(size 1 1)
					(thickness 0.15)
				)
			)
		)
		(property "MPN" ""
			(at 0 0 0)
			(layer "F.Fab")
			(hide yes)
			(effects
				(font
					(size 1 1)
					(thickness 0.15)
				)
			)
		)
		(property "Manufacturer" ""
			(at 0 0 0)
			(layer "F.Fab")
			(hide yes)
			(effects
				(font
					(size 1 1)
					(thickness 0.15)
				)
			)
		)
		(property "Public" "False"
			(at 0 0 0)
			(layer "F.Fab")
			(hide yes)
			(effects
				(font
					(size 1 1)
					(thickness 0.15)
				)
			)
		)
		(sheetname "KR to SFI #2")
		(sheetfile "kr_sfi.kicad_sch")
		(attr exclude_from_pos_files exclude_from_bom)
		(fp_circle
			(center 0 0)
			(end 0.475 0)
			(stroke
				(width 0.05)
				(type default)
			)
			(fill no)
			(layer "F.CrtYd")
		)
		(pad "1" smd circle
			(at 0 0)
			(size 0.75 0.75)
			(layers "F.Cu" "F.Mask")
			(net 756 "Net-(U45A-LS_OK_{OUT_A})")
			(pinfunction "1")
			(pintype "passive")
			(teardrops
				(best_length_ratio 0.4)
				(max_length 1)
				(best_width_ratio 0.9)
				(max_width 2)
				(curved_edges yes)
				(filter_ratio 0.9)
				(enabled yes)
				(allow_two_segments yes)
				(prefer_zone_connections yes)
			)
		)
	)
	(footprint "antmicro-footprints:C_0603_1608Metric"
		(layer "F.Cu")
		(at 177.52 95.69)
		(descr "Capacitor SMD 0603")
		(tags "capacitor 0603")
		(property "Reference" "C72"
			(at -3.32 0.47 0)
			(layer "F.SilkS")
			(effects
				(font
					(size 0.7 0.7)
					(thickness 0.15)
				)
				(justify left bottom)
			)
		)
		(property "Value" "C_22u_16V_0603"
			(at -1.42757 1.770288 0)
			(layer "F.Fab")
			(effects
				(font
					(size 0.7 0.7)
					(thickness 0.15)
				)
				(justify left bottom)
			)
		)
		(property "Datasheet" "https://product.samsungsem.com/mlcc/CL10A226MO7JZN.do"
			(at 0 0 0)
			(layer "F.Fab")
			(hide yes)
			(effects
				(font
					(size 1.27 1.27)
					(thickness 0.15)
				)
			)
		)
		(property "Author" "Antmicro"
			(at 0 0 0)
			(layer "F.Fab")
			(hide yes)
			(effects
				(font
					(size 1 1)
					(thickness 0.15)
				)
			)
		)
		(property "Dielectric" ""
			(at 0 0 0)
			(layer "F.Fab")
			(hide yes)
			(effects
				(font
					(size 1 1)
					(thickness 0.15)
				)
			)
		)
		(property "License" "Apache-2.0"
			(at 0 0 0)
			(layer "F.Fab")
			(hide yes)
			(effects
				(font
					(size 1 1)
					(thickness 0.15)
				)
			)
		)
		(property "MPN" "CL10A226MO7JZNC"
			(at 0 0 0)
			(layer "F.Fab")
			(hide yes)
			(effects
				(font
					(size 1 1)
					(thickness 0.15)
				)
			)
		)
		(property "Manufacturer" "Samsung Electro-Mechanics"
			(at 0 0 0)
			(layer "F.Fab")
			(hide yes)
			(effects
				(font
					(size 1 1)
					(thickness 0.15)
				)
			)
		)
		(property "Public" "False"
			(at 0 0 0)
			(layer "F.Fab")
			(hide yes)
			(effects
				(font
					(size 1 1)
					(thickness 0.15)
				)
			)
		)
		(property "Val" "22u"
			(at 0 0 0)
			(layer "F.Fab")
			(hide yes)
			(effects
				(font
					(size 1 1)
					(thickness 0.15)
				)
			)
		)
		(property "Voltage" "16V"
			(at 0 0 0)
			(layer "F.Fab")
			(hide yes)
			(effects
				(font
					(size 1 1)
					(thickness 0.15)
				)
			)
		)
		(sheetname "M.2 key M #1")
		(sheetfile "m2keym_low.kicad_sch")
		(attr smd)
		(fp_line
			(start -0.15 -0.4)
			(end 0.15 -0.4)
			(stroke
				(width 0.15)
				(type solid)
			)
			(layer "F.SilkS")
		)
		(fp_line
			(start -0.15 0.4)
			(end 0.15 0.4)
			(stroke
				(width 0.15)
				(type solid)
			)
			(layer "F.SilkS")
		)
		(fp_rect
			(start -1.25 -0.65)
			(end 1.25 0.65)
			(stroke
				(width 0.05)
				(type solid)
			)
			(fill no)
			(layer "F.CrtYd")
		)
		(fp_rect
			(start -0.8 -0.4)
			(end 0.8 0.4)
			(stroke
				(width 0.15)
				(type solid)
			)
			(fill no)
			(layer "F.Fab")
		)
		(pad "1" smd roundrect
			(at -0.7 0)
			(size 0.8 1)
			(layers "F.Cu" "F.Mask" "F.Paste")
			(roundrect_rratio 0.2)
			(net 1 "GND")
			(pintype "passive")
			(teardrops
				(best_length_ratio 0.2)
				(max_length 1)
				(best_width_ratio 0.9)
				(max_width 2)
				(curved_edges yes)
				(filter_ratio 0.9)
				(enabled yes)
				(allow_two_segments yes)
				(prefer_zone_connections yes)
			)
		)
		(pad "2" smd roundrect
			(at 0.7 0)
			(size 0.8 1)
			(layers "F.Cu" "F.Mask" "F.Paste")
			(roundrect_rratio 0.2)
			(net 969 "/M.2 key M #1/M2_3V3")
			(pintype "passive")
			(teardrops
				(best_length_ratio 0.2)
				(max_length 1)
				(best_width_ratio 0.9)
				(max_width 2)
				(curved_edges yes)
				(filter_ratio 0.9)
				(enabled yes)
				(allow_two_segments yes)
				(prefer_zone_connections yes)
			)
		)
	)
	(footprint "antmicro-footprints:TP_SMD_0.75mm"
		(layer "F.Cu")
		(at 132.99 129.56)
		(property "Reference" "TP83"
			(at 0.46 -1.25 90)
			(layer "F.SilkS")
			(effects
				(font
					(size 0.7 0.7)
					(thickness 0.15)
				)
				(justify left bottom)
			)
		)
		(property "Value" "TP_0.75mm_SMD"
			(at 0 1.2 0)
			(layer "F.Fab")
			(effects
				(font
					(size 0.7 0.7)
					(thickness 0.15)
				)
				(justify left bottom)
			)
		)
		(property "Author" "Antmicro"
			(at 0 0 0)
			(layer "F.Fab")
			(hide yes)
			(effects
				(font
					(size 1 1)
					(thickness 0.15)
				)
			)
		)
		(property "License" "Apache-2.0"
			(at 0 0 0)
			(layer "F.Fab")
			(hide yes)
			(effects
				(font
					(size 1 1)
					(thickness 0.15)
				)
			)
		)
		(property "MPN" ""
			(at 0 0 0)
			(layer "F.Fab")
			(hide yes)
			(effects
				(font
					(size 1 1)
					(thickness 0.15)
				)
			)
		)
		(property "Manufacturer" ""
			(at 0 0 0)
			(layer "F.Fab")
			(hide yes)
			(effects
				(font
					(size 1 1)
					(thickness 0.15)
				)
			)
		)
		(property "Public" "False"
			(at 0 0 0)
			(layer "F.Fab")
			(hide yes)
			(effects
				(font
					(size 1 1)
					(thickness 0.15)
				)
			)
		)
		(sheetname "KR to SFI #2")
		(sheetfile "kr_sfi.kicad_sch")
		(attr exclude_from_pos_files exclude_from_bom)
		(fp_circle
			(center 0 0)
			(end 0.475 0)
			(stroke
				(width 0.05)
				(type default)
			)
			(fill no)
			(layer "F.CrtYd")
		)
		(pad "1" smd circle
			(at 0 0)
			(size 0.75 0.75)
			(layers "F.Cu" "F.Mask")
			(net 746 "/2xSFP+/KR to SFI #2/~{TRST}")
			(pinfunction "1")
			(pintype "passive")
			(teardrops
				(best_length_ratio 0.4)
				(max_length 1)
				(best_width_ratio 0.9)
				(max_width 2)
				(curved_edges yes)
				(filter_ratio 0.9)
				(enabled yes)
				(allow_two_segments yes)
				(prefer_zone_connections yes)
			)
		)
	)
)
